FILE_TYPE=LIBRARY_PARTS;
TIME=' Created/Modified on Wed Mar 25 10:13:10 2009' ;
primitive 'LTC4307CMS8';
  pin
    'ENABLE':
      PIN_NUMBER='(1)';
      INPUT_LOAD='(-0.01,0.01)';
    'SCL_IN':
      PIN_NUMBER='(3)';
      INPUT_LOAD='(-0.01,0.01)';
      OUTPUT_LOAD='(1.0,-1.0)';
      BIDIRECTIONAL='TRUE';
    'SDA_IN':
      PIN_NUMBER='(6)';
      INPUT_LOAD='(-0.01,0.01)';
      OUTPUT_LOAD='(1.0,-1.0)';
      BIDIRECTIONAL='TRUE';
    'SCL_OUT':
      PIN_NUMBER='(2)';
      INPUT_LOAD='(-0.01,0.01)';
      OUTPUT_LOAD='(1.0,-1.0)';
      BIDIRECTIONAL='TRUE';
    'SDA_OUT':
      PIN_NUMBER='(7)';
      INPUT_LOAD='(-0.01,0.01)';
      OUTPUT_LOAD='(1.0,-1.0)';
      BIDIRECTIONAL='TRUE';
    'READY':
      PIN_NUMBER='(5)';
      OUTPUT_LOAD='(1.0,-1.0)';
    'GND':
      PIN_NUMBER='(4)';
      PINUSE='POWER';
    'VCC':
      PIN_NUMBER='(8)';
      PINUSE='POWER';
  end_pin;
  body
    CLASS='IC';
    PART_NAME='LTC4307CMS8';
    PHYS_DES_PREFIX='U';
  end_body;
end_primitive;
END.
